(kicad_pcb
	(version 20260206)
	(generator "pcbnew")
	(generator_version "10.0")
	(general
		(thickness 1.6)
		(legacy_teardrops no)
	)
	(paper "A4")
	(title_block
		(title "Bryce Canyon_R.DPB_16317-1_OCP.brd")
		(comment 1 "Bryce Canyon / footprints 767-773 of 2099")
	)
	(layers
		(0 "F.Cu" signal "TOP")
		(4 "In1.Cu" signal "L2GND")
		(6 "In2.Cu" signal "L3")
		(8 "In3.Cu" signal "L4VCC")
		(10 "In4.Cu" signal "L5VCC")
		(12 "In5.Cu" signal "L6")
		(14 "In6.Cu" signal "L7GND")
		(2 "B.Cu" signal "BOTTOM")
		(9 "F.Adhes" user "F.Adhesive")
		(11 "B.Adhes" user "B.Adhesive")
		(13 "F.Paste" user "Package Geometry/Pastemask Top")
		(15 "B.Paste" user "Package Geometry/Pastemask Bottom")
		(5 "F.SilkS" user "Ref Des/Silkscreen Top")
		(7 "B.SilkS" user "Ref Des/Silkscreen Bottom")
		(1 "F.Mask" user "Board Geometry/Soldermask Top")
		(3 "B.Mask" user "Board Geometry/Soldermask Bottom")
		(17 "Dwgs.User" user "User.Drawings")
		(19 "Cmts.User" user "User.Comments")
		(21 "Eco1.User" user "User.Eco1")
		(23 "Eco2.User" user "User.Eco2")
		(25 "Edge.Cuts" user "Board Geometry/Outline")
		(27 "Margin" user)
		(31 "F.CrtYd" user "Package Geometry/Place Bound Top")
		(29 "B.CrtYd" user "Package Geometry/Place Bound Bottom")
		(35 "F.Fab" user "Ref Des/Assembly Top")
		(33 "B.Fab" user "Ref Des/Assembly Bottom")
	)
	(footprint ""
		(layer "F.Cu")
		(at 403.351746 -97.390204 -90)
		(property "Reference" "R481"
			(at 0 0 270)
			(layer "F.SilkS")
			(hide yes)
			(effects
				(font
					(size 1.27 1.27)
				)
			)
		)
		(property "Value" "4K7R2F-GP"
			(at 0.064008 -3.993896 270)
			(unlocked yes)
			(layer "F.Fab")
			(hide yes)
			(effects
				(font
					(size 1.016 1.016)
					(thickness 0.1524)
				)
			)
		)
		(property "Device Type" "R402H16"
			(at 0.064008 -5.517896 270)
			(unlocked yes)
			(layer "F.Fab")
			(hide yes)
			(effects
				(font
					(size 1.016 1.016)
					(thickness 0.1524)
				)
			)
		)
		(duplicate_pad_numbers_are_jumpers no)
		(fp_line
			(start -0.508 -0.9398)
			(end -0.508 0.9398)
			(stroke
				(width 0.1524)
				(type default)
			)
			(layer "F.SilkS")
		)
		(fp_line
			(start 0.508 -0.9398)
			(end -0.508 -0.9398)
			(stroke
				(width 0.1524)
				(type default)
			)
			(layer "F.SilkS")
		)
		(fp_rect
			(start -0.508 0.9398)
			(end 0.508 -0.9398)
			(stroke
				(width 0)
				(type default)
			)
			(fill no)
			(layer "F.CrtYd")
		)
		(fp_rect
			(start -0.508 0.9398)
			(end 0.508 -0.9398)
			(stroke
				(width 0)
				(type default)
			)
			(fill no)
			(layer "F.Fab")
		)
		(pad "1" smd custom
			(at 0 -0.4445 270)
			(size 0.1397 0.1397)
			(layers "F.Cu" "F.Mask" "F.Paste")
			(net "DRIVE_B_21_ACT")
			(options
				(clearance outline)
				(anchor circle)
			)
			(primitives
				(gr_poly
					(pts
						(arc
							(start -0.1778 -0.2794)
							(mid -0.249642 -0.249642)
							(end -0.2794 -0.1778)
						)
						(arc
							(start -0.2794 0.1778)
							(mid -0.249642 0.249642)
							(end -0.1778 0.2794)
						)
						(arc
							(start 0.1778 0.2794)
							(mid 0.249642 0.249642)
							(end 0.2794 0.1778)
						)
						(arc
							(start 0.2794 -0.1778)
							(mid 0.249642 -0.249642)
							(end 0.1778 -0.2794)
						)
					)
					(width 0)
					(fill yes)
				)
			)
		)
		(pad "2" smd custom
			(at 0 0.4445 270)
			(size 0.1397 0.1397)
			(layers "F.Cu" "F.Mask" "F.Paste")
			(net "GND")
			(options
				(clearance outline)
				(anchor circle)
			)
			(primitives
				(gr_poly
					(pts
						(arc
							(start -0.1778 -0.2794)
							(mid -0.249642 -0.249642)
							(end -0.2794 -0.1778)
						)
						(arc
							(start -0.2794 0.1778)
							(mid -0.249642 0.249642)
							(end -0.1778 0.2794)
						)
						(arc
							(start 0.1778 0.2794)
							(mid 0.249642 0.249642)
							(end 0.2794 0.1778)
						)
						(arc
							(start 0.2794 -0.1778)
							(mid 0.249642 -0.249642)
							(end 0.1778 -0.2794)
						)
					)
					(width 0)
					(fill yes)
				)
			)
		)
	)
	(footprint ""
		(layer "F.Cu")
		(at 397.129 -17.145 180)
		(property "Reference" "R822"
			(at 0 0 180)
			(layer "F.SilkS")
			(hide yes)
			(effects
				(font
					(size 1.27 1.27)
				)
			)
		)
		(property "Value" "200KR2F-L-GP"
			(at 0.064008 -3.993896 180)
			(unlocked yes)
			(layer "F.Fab")
			(hide yes)
			(effects
				(font
					(size 1.016 1.016)
					(thickness 0.1524)
				)
			)
		)
		(property "Device Type" "R402H16"
			(at 0.064008 -5.517896 180)
			(unlocked yes)
			(layer "F.Fab")
			(hide yes)
			(effects
				(font
					(size 1.016 1.016)
					(thickness 0.1524)
				)
			)
		)
		(duplicate_pad_numbers_are_jumpers no)
		(fp_line
			(start 0.508 -0.9398)
			(end -0.508 -0.9398)
			(stroke
				(width 0.1524)
				(type default)
			)
			(layer "F.SilkS")
		)
		(fp_line
			(start -0.508 -0.9398)
			(end -0.508 0.9398)
			(stroke
				(width 0.1524)
				(type default)
			)
			(layer "F.SilkS")
		)
		(fp_rect
			(start -0.508 0.9398)
			(end 0.508 -0.9398)
			(stroke
				(width 0)
				(type default)
			)
			(fill no)
			(layer "F.CrtYd")
		)
		(fp_rect
			(start -0.508 0.9398)
			(end 0.508 -0.9398)
			(stroke
				(width 0)
				(type default)
			)
			(fill no)
			(layer "F.Fab")
		)
		(pad "1" smd custom
			(at 0 -0.4445 180)
			(size 0.1397 0.1397)
			(layers "F.Cu" "F.Mask" "F.Paste")
			(net "SW_HDD_R32")
			(options
				(clearance outline)
				(anchor circle)
			)
			(primitives
				(gr_poly
					(pts
						(arc
							(start -0.1778 -0.2794)
							(mid -0.249642 -0.249642)
							(end -0.2794 -0.1778)
						)
						(arc
							(start -0.2794 0.1778)
							(mid -0.249642 0.249642)
							(end -0.1778 0.2794)
						)
						(arc
							(start 0.1778 0.2794)
							(mid 0.249642 0.249642)
							(end 0.2794 0.1778)
						)
						(arc
							(start 0.2794 -0.1778)
							(mid 0.249642 -0.249642)
							(end 0.1778 -0.2794)
						)
					)
					(width 0)
					(fill yes)
				)
			)
		)
		(pad "2" smd custom
			(at 0 0.4445 180)
			(size 0.1397 0.1397)
			(layers "F.Cu" "F.Mask" "F.Paste")
			(net "SW_HDD_N32")
			(options
				(clearance outline)
				(anchor circle)
			)
			(primitives
				(gr_poly
					(pts
						(arc
							(start -0.1778 -0.2794)
							(mid -0.249642 -0.249642)
							(end -0.2794 -0.1778)
						)
						(arc
							(start -0.2794 0.1778)
							(mid -0.249642 0.249642)
							(end -0.1778 0.2794)
						)
						(arc
							(start 0.1778 0.2794)
							(mid 0.249642 0.249642)
							(end 0.2794 0.1778)
						)
						(arc
							(start 0.2794 -0.1778)
							(mid 0.249642 -0.249642)
							(end 0.1778 -0.2794)
						)
					)
					(width 0)
					(fill yes)
				)
			)
		)
	)
	(footprint ""
		(layer "F.Cu")
		(at 54.0004 -246.3038 -90)
		(property "Reference" "R182"
			(at 0 0 270)
			(layer "F.SilkS")
			(hide yes)
			(effects
				(font
					(size 1.27 1.27)
				)
			)
		)
		(property "Value" "0R2J-2-GP"
			(at 0.064008 -3.993896 270)
			(unlocked yes)
			(layer "F.Fab")
			(hide yes)
			(effects
				(font
					(size 1.016 1.016)
					(thickness 0.1524)
				)
			)
		)
		(property "Device Type" "R402H16"
			(at 0.064008 -5.517896 270)
			(unlocked yes)
			(layer "F.Fab")
			(hide yes)
			(effects
				(font
					(size 1.016 1.016)
					(thickness 0.1524)
				)
			)
		)
		(duplicate_pad_numbers_are_jumpers no)
		(fp_line
			(start -0.508 -0.9398)
			(end -0.508 0.9398)
			(stroke
				(width 0.1524)
				(type default)
			)
			(layer "F.SilkS")
		)
		(fp_line
			(start 0.508 -0.9398)
			(end -0.508 -0.9398)
			(stroke
				(width 0.1524)
				(type default)
			)
			(layer "F.SilkS")
		)
		(fp_rect
			(start -0.508 0.9398)
			(end 0.508 -0.9398)
			(stroke
				(width 0)
				(type default)
			)
			(fill no)
			(layer "F.CrtYd")
		)
		(fp_rect
			(start -0.508 0.9398)
			(end 0.508 -0.9398)
			(stroke
				(width 0)
				(type default)
			)
			(fill no)
			(layer "F.Fab")
		)
		(pad "1" smd custom
			(at 0 -0.4445 270)
			(size 0.1397 0.1397)
			(layers "F.Cu" "F.Mask" "F.Paste")
			(net "DRIVE_B_1_PWR")
			(options
				(clearance outline)
				(anchor circle)
			)
			(primitives
				(gr_poly
					(pts
						(arc
							(start -0.1778 -0.2794)
							(mid -0.249642 -0.249642)
							(end -0.2794 -0.1778)
						)
						(arc
							(start -0.2794 0.1778)
							(mid -0.249642 0.249642)
							(end -0.1778 0.2794)
						)
						(arc
							(start 0.1778 0.2794)
							(mid 0.249642 0.249642)
							(end 0.2794 0.1778)
						)
						(arc
							(start 0.2794 -0.1778)
							(mid 0.249642 -0.249642)
							(end 0.1778 -0.2794)
						)
					)
					(width 0)
					(fill yes)
				)
			)
		)
		(pad "2" smd custom
			(at 0 0.4445 270)
			(size 0.1397 0.1397)
			(layers "F.Cu" "F.Mask" "F.Paste")
			(net "SW_PWR_R_HDD1")
			(options
				(clearance outline)
				(anchor circle)
			)
			(primitives
				(gr_poly
					(pts
						(arc
							(start -0.1778 -0.2794)
							(mid -0.249642 -0.249642)
							(end -0.2794 -0.1778)
						)
						(arc
							(start -0.2794 0.1778)
							(mid -0.249642 0.249642)
							(end -0.1778 0.2794)
						)
						(arc
							(start 0.1778 0.2794)
							(mid 0.249642 0.249642)
							(end 0.2794 0.1778)
						)
						(arc
							(start 0.2794 -0.1778)
							(mid 0.249642 -0.249642)
							(end 0.1778 -0.2794)
						)
					)
					(width 0)
					(fill yes)
				)
			)
		)
	)
	(footprint ""
		(layer "F.Cu")
		(at 45.7962 -214.757 180)
		(property "Reference" "Q220"
			(at 0 0 180)
			(layer "F.SilkS")
			(hide yes)
			(effects
				(font
					(size 1.27 1.27)
				)
			)
		)
		(property "Value" "2N7002K-2-GP"
			(at 0.127 -8.9662 180)
			(unlocked yes)
			(layer "F.Fab")
			(hide yes)
			(effects
				(font
					(size 1.016 1.016)
					(thickness 0.1524)
				)
			)
		)
		(property "Device Type" "SOT23DGS2D4H44"
			(at 0.127 -10.4902 180)
			(unlocked yes)
			(layer "F.Fab")
			(hide yes)
			(effects
				(font
					(size 1.016 1.016)
					(thickness 0.1524)
				)
			)
		)
		(duplicate_pad_numbers_are_jumpers no)
		(fp_line
			(start 1.651 1.778)
			(end 1.651 -1.778)
			(stroke
				(width 0.1524)
				(type default)
			)
			(layer "F.SilkS")
		)
		(fp_line
			(start 1.651 -1.778)
			(end -1.651 -1.778)
			(stroke
				(width 0.1524)
				(type default)
			)
			(layer "F.SilkS")
		)
		(fp_line
			(start -1.651 1.778)
			(end 1.651 1.778)
			(stroke
				(width 0.1524)
				(type default)
			)
			(layer "F.SilkS")
		)
		(fp_line
			(start -1.651 -1.778)
			(end -1.651 1.778)
			(stroke
				(width 0.1524)
				(type default)
			)
			(layer "F.SilkS")
		)
		(fp_poly
			(pts
				(xy -1.778 1.8796) (xy -1.778 -1.8796) (xy 1.778 -1.8796) (xy 1.778 1.8796)
			)
			(stroke
				(width 0)
				(type default)
			)
			(fill no)
			(layer "F.CrtYd")
		)
		(fp_poly
			(pts
				(xy -1.778 1.8796) (xy -1.778 -1.8796) (xy 1.778 -1.8796) (xy 1.778 1.8796)
			)
			(stroke
				(width 0)
				(type default)
			)
			(fill no)
			(layer "F.Fab")
		)
		(pad "D" smd custom
			(at 0 -0.9525 180)
			(size 0.1905 0.1905)
			(layers "F.Cu" "F.Mask" "F.Paste")
			(net "FLT_HDD1_N")
			(options
				(clearance outline)
				(anchor circle)
			)
			(primitives
				(gr_poly
					(pts
						(arc
							(start -0.1778 0.5715)
							(mid -0.321484 0.511984)
							(end -0.381 0.3683)
						)
						(arc
							(start -0.381 -0.3683)
							(mid -0.321484 -0.511984)
							(end -0.1778 -0.5715)
						)
						(arc
							(start 0.1778 -0.5715)
							(mid 0.321484 -0.511984)
							(end 0.381 -0.3683)
						)
						(arc
							(start 0.381 0.3683)
							(mid 0.321484 0.511984)
							(end 0.1778 0.5715)
						)
					)
					(width 0)
					(fill yes)
				)
			)
		)
		(pad "G" smd custom
			(at -0.98425 0.9525 180)
			(size 0.1905 0.1905)
			(layers "F.Cu" "F.Mask" "F.Paste")
			(net "DRIVE_B_1_FLT_LED")
			(options
				(clearance outline)
				(anchor circle)
			)
			(primitives
				(gr_poly
					(pts
						(arc
							(start -0.1778 0.5715)
							(mid -0.321484 0.511984)
							(end -0.381 0.3683)
						)
						(arc
							(start -0.381 -0.3683)
							(mid -0.321484 -0.511984)
							(end -0.1778 -0.5715)
						)
						(arc
							(start 0.1778 -0.5715)
							(mid 0.321484 -0.511984)
							(end 0.381 -0.3683)
						)
						(arc
							(start 0.381 0.3683)
							(mid 0.321484 0.511984)
							(end 0.1778 0.5715)
						)
					)
					(width 0)
					(fill yes)
				)
			)
		)
		(pad "S" smd custom
			(at 0.98425 0.9525 180)
			(size 0.1905 0.1905)
			(layers "F.Cu" "F.Mask" "F.Paste")
			(net "GND")
			(options
				(clearance outline)
				(anchor circle)
			)
			(primitives
				(gr_poly
					(pts
						(arc
							(start -0.1778 0.5715)
							(mid -0.321484 0.511984)
							(end -0.381 0.3683)
						)
						(arc
							(start -0.381 -0.3683)
							(mid -0.321484 -0.511984)
							(end -0.1778 -0.5715)
						)
						(arc
							(start 0.1778 -0.5715)
							(mid 0.321484 -0.511984)
							(end 0.381 -0.3683)
						)
						(arc
							(start 0.381 0.3683)
							(mid 0.321484 0.511984)
							(end 0.1778 0.5715)
						)
					)
					(width 0)
					(fill yes)
				)
			)
		)
	)
	(footprint ""
		(layer "F.Cu")
		(at 24.22017 -228.351842 -90)
		(property "Reference" "R1105"
			(at 0 0 270)
			(layer "F.SilkS")
			(hide yes)
			(effects
				(font
					(size 1.27 1.27)
				)
			)
		)
		(property "Value" "15KR2F-GP"
			(at 0.064008 -3.993896 270)
			(unlocked yes)
			(layer "F.Fab")
			(hide yes)
			(effects
				(font
					(size 1.016 1.016)
					(thickness 0.1524)
				)
			)
		)
		(property "Device Type" "R402H16"
			(at 0.064008 -5.517896 270)
			(unlocked yes)
			(layer "F.Fab")
			(hide yes)
			(effects
				(font
					(size 1.016 1.016)
					(thickness 0.1524)
				)
			)
		)
		(duplicate_pad_numbers_are_jumpers no)
		(fp_line
			(start -0.508 -0.9398)
			(end -0.508 0.9398)
			(stroke
				(width 0.1524)
				(type default)
			)
			(layer "F.SilkS")
		)
		(fp_line
			(start 0.508 -0.9398)
			(end -0.508 -0.9398)
			(stroke
				(width 0.1524)
				(type default)
			)
			(layer "F.SilkS")
		)
		(fp_rect
			(start -0.508 0.9398)
			(end 0.508 -0.9398)
			(stroke
				(width 0)
				(type default)
			)
			(fill no)
			(layer "F.CrtYd")
		)
		(fp_rect
			(start -0.508 0.9398)
			(end 0.508 -0.9398)
			(stroke
				(width 0)
				(type default)
			)
			(fill no)
			(layer "F.Fab")
		)
		(pad "1" smd custom
			(at 0 -0.4445 270)
			(size 0.1397 0.1397)
			(layers "F.Cu" "F.Mask" "F.Paste")
			(net "P5V_B_1_PGOOD")
			(options
				(clearance outline)
				(anchor circle)
			)
			(primitives
				(gr_poly
					(pts
						(arc
							(start -0.1778 -0.2794)
							(mid -0.249642 -0.249642)
							(end -0.2794 -0.1778)
						)
						(arc
							(start -0.2794 0.1778)
							(mid -0.249642 0.249642)
							(end -0.1778 0.2794)
						)
						(arc
							(start 0.1778 0.2794)
							(mid 0.249642 0.249642)
							(end 0.2794 0.1778)
						)
						(arc
							(start 0.2794 -0.1778)
							(mid 0.249642 -0.249642)
							(end 0.1778 -0.2794)
						)
					)
					(width 0)
					(fill yes)
				)
			)
		)
		(pad "2" smd custom
			(at 0 0.4445 270)
			(size 0.1397 0.1397)
			(layers "F.Cu" "F.Mask" "F.Paste")
			(net "GND")
			(options
				(clearance outline)
				(anchor circle)
			)
			(primitives
				(gr_poly
					(pts
						(arc
							(start -0.1778 -0.2794)
							(mid -0.249642 -0.249642)
							(end -0.2794 -0.1778)
						)
						(arc
							(start -0.2794 0.1778)
							(mid -0.249642 0.249642)
							(end -0.1778 0.2794)
						)
						(arc
							(start 0.1778 0.2794)
							(mid 0.249642 0.249642)
							(end 0.2794 0.1778)
						)
						(arc
							(start 0.2794 -0.1778)
							(mid 0.249642 -0.249642)
							(end 0.1778 -0.2794)
						)
					)
					(width 0)
					(fill yes)
				)
			)
		)
	)
	(footprint ""
		(layer "F.Cu")
		(at 440.908186 -113.996978)
		(property "Reference" "R1158"
			(at 0 0 0)
			(layer "F.SilkS")
			(hide yes)
			(effects
				(font
					(size 1.27 1.27)
				)
			)
		)
		(property "Value" "0R3J-0-U-GP"
			(at -0.0254 -2.5146 0)
			(unlocked yes)
			(layer "F.Fab")
			(hide yes)
			(effects
				(font
					(size 1.016 1.016)
					(thickness 0.1524)
				)
			)
		)
		(property "Device Type" "R603H22"
			(at -0.0254 -4.0386 0)
			(unlocked yes)
			(layer "F.Fab")
			(hide yes)
			(effects
				(font
					(size 1.016 1.016)
					(thickness 0.1524)
				)
			)
		)
		(duplicate_pad_numbers_are_jumpers no)
		(fp_line
			(start -0.4826 0)
			(end -0.2032 0)
			(stroke
				(width 0.2032)
				(type default)
			)
			(layer "F.SilkS")
		)
		(fp_line
			(start 0.2032 0)
			(end 0.4826 0)
			(stroke
				(width 0.2032)
				(type default)
			)
			(layer "F.SilkS")
		)
		(fp_rect
			(start -0.5842 1.3335)
			(end 0.5842 -1.3335)
			(stroke
				(width 0)
				(type default)
			)
			(fill no)
			(layer "F.CrtYd")
		)
		(fp_rect
			(start -0.5842 1.3335)
			(end 0.5842 -1.3335)
			(stroke
				(width 0)
				(type default)
			)
			(fill no)
			(layer "F.Fab")
		)
		(pad "1" smd custom
			(at 0 -0.762)
			(size 0.2159 0.2159)
			(layers "F.Cu" "F.Mask" "F.Paste")
			(net "P5V_B_4_VBST")
			(options
				(clearance outline)
				(anchor circle)
			)
			(primitives
				(gr_poly
					(pts
						(arc
							(start -0.3302 -0.4318)
							(mid -0.402042 -0.402042)
							(end -0.4318 -0.3302)
						)
						(arc
							(start -0.4318 0.3302)
							(mid -0.402042 0.402042)
							(end -0.3302 0.4318)
						)
						(arc
							(start 0.3302 0.4318)
							(mid 0.402042 0.402042)
							(end 0.4318 0.3302)
						)
						(arc
							(start 0.4318 -0.3302)
							(mid 0.402042 -0.402042)
							(end 0.3302 -0.4318)
						)
					)
					(width 0)
					(fill yes)
				)
			)
		)
		(pad "2" smd custom
			(at 0 0.762)
			(size 0.2159 0.2159)
			(layers "F.Cu" "F.Mask" "F.Paste")
			(net "P5V_B_4_VBST_RC")
			(options
				(clearance outline)
				(anchor circle)
			)
			(primitives
				(gr_poly
					(pts
						(arc
							(start -0.3302 -0.4318)
							(mid -0.402042 -0.402042)
							(end -0.4318 -0.3302)
						)
						(arc
							(start -0.4318 0.3302)
							(mid -0.402042 0.402042)
							(end -0.3302 0.4318)
						)
						(arc
							(start 0.3302 0.4318)
							(mid 0.402042 0.402042)
							(end 0.4318 0.3302)
						)
						(arc
							(start 0.4318 -0.3302)
							(mid 0.402042 -0.402042)
							(end 0.3302 -0.4318)
						)
					)
					(width 0)
					(fill yes)
				)
			)
		)
	)
	(footprint ""
		(layer "F.Cu")
		(at 240.919 -215.265 180)
		(property "Reference" "R80"
			(at 0 0 180)
			(layer "F.SilkS")
			(hide yes)
			(effects
				(font
					(size 1.27 1.27)
				)
			)
		)
		(property "Value" "4K7R2F-GP"
			(at 0.064008 -3.993896 180)
			(unlocked yes)
			(layer "F.Fab")
			(hide yes)
			(effects
				(font
					(size 1.016 1.016)
					(thickness 0.1524)
				)
			)
		)
		(property "Device Type" "R402H16"
			(at 0.064008 -5.517896 180)
			(unlocked yes)
			(layer "F.Fab")
			(hide yes)
			(effects
				(font
					(size 1.016 1.016)
					(thickness 0.1524)
				)
			)
		)
		(duplicate_pad_numbers_are_jumpers no)
		(fp_line
			(start 0.508 -0.9398)
			(end -0.508 -0.9398)
			(stroke
				(width 0.1524)
				(type default)
			)
			(layer "F.SilkS")
		)
		(fp_line
			(start -0.508 -0.9398)
			(end -0.508 0.9398)
			(stroke
				(width 0.1524)
				(type default)
			)
			(layer "F.SilkS")
		)
		(fp_rect
			(start -0.508 0.9398)
			(end 0.508 -0.9398)
			(stroke
				(width 0)
				(type default)
			)
			(fill no)
			(layer "F.CrtYd")
		)
		(fp_rect
			(start -0.508 0.9398)
			(end 0.508 -0.9398)
			(stroke
				(width 0)
				(type default)
			)
			(fill no)
			(layer "F.Fab")
		)
		(pad "1" smd custom
			(at 0 -0.4445 180)
			(size 0.1397 0.1397)
			(layers "F.Cu" "F.Mask" "F.Paste")
			(net "P3V3_STBY_B")
			(options
				(clearance outline)
				(anchor circle)
			)
			(primitives
				(gr_poly
					(pts
						(arc
							(start -0.1778 -0.2794)
							(mid -0.249642 -0.249642)
							(end -0.2794 -0.1778)
						)
						(arc
							(start -0.2794 0.1778)
							(mid -0.249642 0.249642)
							(end -0.1778 0.2794)
						)
						(arc
							(start 0.1778 0.2794)
							(mid 0.249642 0.249642)
							(end 0.2794 0.1778)
						)
						(arc
							(start 0.2794 -0.1778)
							(mid 0.249642 -0.249642)
							(end 0.1778 -0.2794)
						)
					)
					(width 0)
					(fill yes)
				)
			)
		)
		(pad "2" smd custom
			(at 0 0.4445 180)
			(size 0.1397 0.1397)
			(layers "F.Cu" "F.Mask" "F.Paste")
			(net "IO_EXP3_A0")
			(options
				(clearance outline)
				(anchor circle)
			)
			(primitives
				(gr_poly
					(pts
						(arc
							(start -0.1778 -0.2794)
							(mid -0.249642 -0.249642)
							(end -0.2794 -0.1778)
						)
						(arc
							(start -0.2794 0.1778)
							(mid -0.249642 0.249642)
							(end -0.1778 0.2794)
						)
						(arc
							(start 0.1778 0.2794)
							(mid 0.249642 0.249642)
							(end 0.2794 0.1778)
						)
						(arc
							(start 0.2794 -0.1778)
							(mid 0.249642 -0.249642)
							(end 0.1778 -0.2794)
						)
					)
					(width 0)
					(fill yes)
				)
			)
		)
	)
)
